(kicad_pcb
	(version 20260206)
	(generator "pcbnew")
	(generator_version "10.0")
	(general
		(thickness 1.6)
		(legacy_teardrops no)
	)
	(paper "A4")
	(title_block
		(title "dpb — 14545-sa.0730WZS0815.brd")
		(comment 1 "Honey Badger (Wiwynn) / footprints 34-40 of 1066")
	)
	(layers
		(0 "F.Cu" signal "TOP")
		(4 "In1.Cu" signal "L2GND")
		(6 "In2.Cu" signal "L3")
		(8 "In3.Cu" signal "L4VCC")
		(10 "In4.Cu" signal "L5VCC")
		(12 "In5.Cu" signal "L6")
		(14 "In6.Cu" signal "L7GND")
		(2 "B.Cu" signal "BOTTOM")
		(9 "F.Adhes" user "F.Adhesive")
		(11 "B.Adhes" user "B.Adhesive")
		(13 "F.Paste" user "Package Geometry/Pastemask Top")
		(15 "B.Paste" user "Package Geometry/Pastemask Bottom")
		(5 "F.SilkS" user "Ref Des/Silkscreen Top")
		(7 "B.SilkS" user "Ref Des/Silkscreen Bottom")
		(1 "F.Mask" user "Board Geometry/Soldermask Top")
		(3 "B.Mask" user "Board Geometry/Soldermask Bottom")
		(17 "Dwgs.User" user "User.Drawings")
		(19 "Cmts.User" user "User.Comments")
		(21 "Eco1.User" user "User.Eco1")
		(23 "Eco2.User" user "User.Eco2")
		(25 "Edge.Cuts" user "Board Geometry/Outline")
		(27 "Margin" user)
		(31 "F.CrtYd" user "Package Geometry/Place Bound Top")
		(29 "B.CrtYd" user "Package Geometry/Place Bound Bottom")
		(35 "F.Fab" user "Ref Des/Assembly Top")
		(33 "B.Fab" user "Ref Des/Assembly Bottom")
	)
	(footprint ""
		(layer "F.Cu")
		(at 55.625492 -80.038956 180)
		(property "Reference" "C250"
			(at 0 0 180)
			(layer "F.SilkS")
			(hide yes)
			(effects
				(font
					(size 1.27 1.27)
				)
			)
		)
		(property "Value" "SC1U16V3KX-5GP"
			(at 0 -2.8194 180)
			(unlocked yes)
			(layer "F.Fab")
			(hide yes)
			(effects
				(font
					(size 1.016 1.016)
					(thickness 0.1524)
				)
			)
		)
		(property "Device Type" "C603H36"
			(at 0 -4.3434 180)
			(unlocked yes)
			(layer "F.Fab")
			(hide yes)
			(effects
				(font
					(size 1.016 1.016)
					(thickness 0.1524)
				)
			)
		)
		(duplicate_pad_numbers_are_jumpers no)
		(fp_line
			(start 0.508 0)
			(end -0.508 0)
			(stroke
				(width 0.2032)
				(type default)
			)
			(layer "F.SilkS")
		)
		(fp_rect
			(start -0.5842 1.3335)
			(end 0.5842 -1.3335)
			(stroke
				(width 0)
				(type default)
			)
			(fill no)
			(layer "F.CrtYd")
		)
		(fp_rect
			(start -0.5842 1.3335)
			(end 0.5842 -1.3335)
			(stroke
				(width 0)
				(type default)
			)
			(fill no)
			(layer "F.Fab")
		)
		(pad "1" smd custom
			(at 0 -0.762 180)
			(size 0.2159 0.2159)
			(layers "F.Cu" "F.Mask" "F.Paste")
			(net "P5V_HDD9")
			(options
				(clearance outline)
				(anchor circle)
			)
			(primitives
				(gr_poly
					(pts
						(arc
							(start -0.3302 -0.4318)
							(mid -0.402042 -0.402042)
							(end -0.4318 -0.3302)
						)
						(arc
							(start -0.4318 0.3302)
							(mid -0.402042 0.402042)
							(end -0.3302 0.4318)
						)
						(arc
							(start 0.3302 0.4318)
							(mid 0.402042 0.402042)
							(end 0.4318 0.3302)
						)
						(arc
							(start 0.4318 -0.3302)
							(mid 0.402042 -0.402042)
							(end 0.3302 -0.4318)
						)
					)
					(width 0)
					(fill yes)
				)
			)
		)
		(pad "2" smd custom
			(at 0 0.762 180)
			(size 0.2159 0.2159)
			(layers "F.Cu" "F.Mask" "F.Paste")
			(net "GND")
			(options
				(clearance outline)
				(anchor circle)
			)
			(primitives
				(gr_poly
					(pts
						(arc
							(start -0.3302 -0.4318)
							(mid -0.402042 -0.402042)
							(end -0.4318 -0.3302)
						)
						(arc
							(start -0.4318 0.3302)
							(mid -0.402042 0.402042)
							(end -0.3302 0.4318)
						)
						(arc
							(start 0.3302 0.4318)
							(mid 0.402042 0.402042)
							(end 0.4318 0.3302)
						)
						(arc
							(start 0.4318 -0.3302)
							(mid 0.402042 -0.402042)
							(end 0.3302 -0.4318)
						)
					)
					(width 0)
					(fill yes)
				)
			)
		)
	)
	(footprint ""
		(layer "F.Cu")
		(at 227.499926 -453.159876 180)
		(property "Reference" "LED1"
			(at 0 0 180)
			(layer "F.SilkS")
			(hide yes)
			(effects
				(font
					(size 1.27 1.27)
				)
			)
		)
		(property "Value" "LED-RB-4-GP"
			(at 5.88899 1.80848 180)
			(unlocked yes)
			(layer "F.Fab")
			(hide yes)
			(effects
				(font
					(size 1.016 1.016)
					(thickness 0.1524)
				)
			)
		)
		(property "Device Type" "LED1613-4PH20"
			(at 5.88899 0.28448 180)
			(unlocked yes)
			(layer "F.Fab")
			(hide yes)
			(effects
				(font
					(size 1.016 1.016)
					(thickness 0.1524)
				)
			)
		)
		(duplicate_pad_numbers_are_jumpers no)
		(fp_line
			(start 1.4478 0.9652)
			(end -1.4478 0.9652)
			(stroke
				(width 0.1524)
				(type default)
			)
			(layer "F.SilkS")
		)
		(fp_line
			(start 1.4478 -0.9652)
			(end 1.4478 0.9652)
			(stroke
				(width 0.1524)
				(type default)
			)
			(layer "F.SilkS")
		)
		(fp_line
			(start -1.4478 0.9652)
			(end -1.4478 -0.9652)
			(stroke
				(width 0.1524)
				(type default)
			)
			(layer "F.SilkS")
		)
		(fp_line
			(start -1.4478 0.9652)
			(end -1.4478 -0.9652)
			(stroke
				(width 0.508)
				(type default)
			)
			(layer "F.SilkS")
		)
		(fp_line
			(start -1.4478 -0.9652)
			(end 1.4478 -0.9652)
			(stroke
				(width 0.1524)
				(type default)
			)
			(layer "F.SilkS")
		)
		(fp_rect
			(start -0.8001 0.6477)
			(end 0.8001 -0.6477)
			(stroke
				(width 0)
				(type default)
			)
			(fill no)
			(layer "F.CrtYd")
		)
		(fp_poly
			(pts
				(xy -1.7018 1.2192) (xy -1.7018 -0.06223) (xy -0.8001 -0.06223) (xy -0.8001 0.6477) (xy 0.8001 0.6477)
				(xy 0.8001 -0.6477) (xy -0.8001 -0.6477) (xy -0.8001 -0.0635) (xy -1.7018 -0.0635) (xy -1.7018 -1.2192)
				(xy 1.7018 -1.2192) (xy 1.7018 1.2192)
			)
			(stroke
				(width 0)
				(type default)
			)
			(fill no)
			(layer "F.CrtYd")
		)
		(fp_rect
			(start -1.7018 1.2192)
			(end 1.7018 -1.2192)
			(stroke
				(width 0)
				(type default)
			)
			(fill no)
			(layer "F.Fab")
		)
		(pad "1" smd rect
			(at -0.73025 0.4064 180)
			(size 0.9144 0.6096)
			(layers "F.Cu" "F.Mask" "F.Paste")
			(net "DRV_ACT_NET0")
		)
		(pad "2" smd rect
			(at -0.73025 -0.4064 180)
			(size 0.9144 0.6096)
			(layers "F.Cu" "F.Mask" "F.Paste")
			(net "FLT_NET_HDD0")
		)
		(pad "3" smd rect
			(at 0.73025 -0.4064 180)
			(size 0.9144 0.6096)
			(layers "F.Cu" "F.Mask" "F.Paste")
			(net "FLT_HDD0")
		)
		(pad "4" smd rect
			(at 0.73025 0.4064 180)
			(size 0.9144 0.6096)
			(layers "F.Cu" "F.Mask" "F.Paste")
			(net "DRV_ACT_0")
		)
	)
	(footprint ""
		(layer "F.Cu")
		(at 29.209746 -318.798702 90)
		(property "Reference" "R264"
			(at 0 0 90)
			(layer "F.SilkS")
			(hide yes)
			(effects
				(font
					(size 1.27 1.27)
				)
			)
		)
		(property "Value" "2R2010J-1-GP"
			(at 0.254 -8.0772 90)
			(unlocked yes)
			(layer "F.Fab")
			(hide yes)
			(effects
				(font
					(size 1.016 1.016)
					(thickness 0.1524)
				)
			)
		)
		(property "Device Type" "R2010H28"
			(at 0.254 -9.6774 90)
			(unlocked yes)
			(layer "F.Fab")
			(hide yes)
			(effects
				(font
					(size 1.016 1.016)
					(thickness 0.1524)
				)
			)
		)
		(duplicate_pad_numbers_are_jumpers no)
		(fp_line
			(start 1.651 -3.302)
			(end -1.651 -3.302)
			(stroke
				(width 0.1524)
				(type default)
			)
			(layer "F.SilkS")
		)
		(fp_line
			(start -1.651 -3.302)
			(end -1.651 3.302)
			(stroke
				(width 0.1524)
				(type default)
			)
			(layer "F.SilkS")
		)
		(fp_line
			(start 1.651 3.302)
			(end 1.651 -3.302)
			(stroke
				(width 0.1524)
				(type default)
			)
			(layer "F.SilkS")
		)
		(fp_line
			(start -1.651 3.302)
			(end 1.651 3.302)
			(stroke
				(width 0.1524)
				(type default)
			)
			(layer "F.SilkS")
		)
		(fp_rect
			(start -1.7272 -3.3782)
			(end 1.7272 3.3782)
			(stroke
				(width 0)
				(type default)
			)
			(fill no)
			(layer "F.CrtYd")
		)
		(fp_poly
			(pts
				(xy 1.7272 3.3782) (xy 1.7272 -3.3782) (xy -1.7272 -3.3782) (xy -1.7272 3.3782)
			)
			(stroke
				(width 0)
				(type default)
			)
			(fill no)
			(layer "F.Fab")
		)
		(pad "1" smd rect
			(at 0 -2.3495 90)
			(size 2.794 1.143)
			(layers "F.Cu" "F.Mask" "F.Paste")
			(net "12V_PRE_11")
		)
		(pad "2" smd rect
			(at 0 2.3495 90)
			(size 2.794 1.143)
			(layers "F.Cu" "F.Mask" "F.Paste")
			(net "P12V_HDD11")
		)
	)
	(footprint ""
		(layer "F.Cu")
		(at 25.298146 -274.7518 90)
		(property "Reference" "R495"
			(at 0 0 90)
			(layer "F.SilkS")
			(hide yes)
			(effects
				(font
					(size 1.27 1.27)
				)
			)
		)
		(property "Value" "4K7R2J-2-GP"
			(at 0.064008 -3.993896 90)
			(unlocked yes)
			(layer "F.Fab")
			(hide yes)
			(effects
				(font
					(size 1.016 1.016)
					(thickness 0.1524)
				)
			)
		)
		(property "Device Type" "R402H16"
			(at 0.064008 -5.517896 90)
			(unlocked yes)
			(layer "F.Fab")
			(hide yes)
			(effects
				(font
					(size 1.016 1.016)
					(thickness 0.1524)
				)
			)
		)
		(duplicate_pad_numbers_are_jumpers no)
		(fp_line
			(start 0.508 -0.9398)
			(end -0.508 -0.9398)
			(stroke
				(width 0.1524)
				(type default)
			)
			(layer "F.SilkS")
		)
		(fp_line
			(start -0.508 -0.9398)
			(end -0.508 0.9398)
			(stroke
				(width 0.1524)
				(type default)
			)
			(layer "F.SilkS")
		)
		(fp_rect
			(start -0.508 0.9398)
			(end 0.508 -0.9398)
			(stroke
				(width 0)
				(type default)
			)
			(fill no)
			(layer "F.CrtYd")
		)
		(fp_rect
			(start -0.508 0.9398)
			(end 0.508 -0.9398)
			(stroke
				(width 0)
				(type default)
			)
			(fill no)
			(layer "F.Fab")
		)
		(pad "1" smd custom
			(at 0 -0.4445 90)
			(size 0.1397 0.1397)
			(layers "F.Cu" "F.Mask" "F.Paste")
			(net "P3V3")
			(options
				(clearance outline)
				(anchor circle)
			)
			(primitives
				(gr_poly
					(pts
						(arc
							(start -0.1778 -0.2794)
							(mid -0.249642 -0.249642)
							(end -0.2794 -0.1778)
						)
						(arc
							(start -0.2794 0.1778)
							(mid -0.249642 0.249642)
							(end -0.1778 0.2794)
						)
						(arc
							(start 0.1778 0.2794)
							(mid 0.249642 0.249642)
							(end 0.2794 0.1778)
						)
						(arc
							(start 0.2794 -0.1778)
							(mid 0.249642 -0.249642)
							(end 0.1778 -0.2794)
						)
					)
					(width 0)
					(fill yes)
				)
			)
		)
		(pad "2" smd custom
			(at 0 0.4445 90)
			(size 0.1397 0.1397)
			(layers "F.Cu" "F.Mask" "F.Paste")
			(net "SAS2X28_B_HDD7_FLT")
			(options
				(clearance outline)
				(anchor circle)
			)
			(primitives
				(gr_poly
					(pts
						(arc
							(start -0.1778 -0.2794)
							(mid -0.249642 -0.249642)
							(end -0.2794 -0.1778)
						)
						(arc
							(start -0.2794 0.1778)
							(mid -0.249642 0.249642)
							(end -0.1778 0.2794)
						)
						(arc
							(start 0.1778 0.2794)
							(mid 0.249642 0.249642)
							(end 0.2794 0.1778)
						)
						(arc
							(start 0.2794 -0.1778)
							(mid 0.249642 -0.249642)
							(end 0.1778 -0.2794)
						)
					)
					(width 0)
					(fill yes)
				)
			)
		)
	)
	(footprint ""
		(layer "F.Cu")
		(at 230.631746 -21.9837 180)
		(property "Reference" "PC9"
			(at 0 0 180)
			(layer "F.SilkS")
			(hide yes)
			(effects
				(font
					(size 1.27 1.27)
				)
			)
		)
		(property "Value" "SC2200P50V2KX-2GP"
			(at 1.1811 -2.7051 180)
			(unlocked yes)
			(layer "F.Fab")
			(hide yes)
			(effects
				(font
					(size 1.016 1.016)
					(thickness 0.1524)
				)
			)
		)
		(property "Device Type" "C402H22"
			(at 1.1811 -4.2291 180)
			(unlocked yes)
			(layer "F.Fab")
			(hide yes)
			(effects
				(font
					(size 1.016 1.016)
					(thickness 0.1524)
				)
			)
		)
		(duplicate_pad_numbers_are_jumpers no)
		(fp_rect
			(start -0.4318 0.9525)
			(end 0.4318 -0.9525)
			(stroke
				(width 0)
				(type default)
			)
			(fill no)
			(layer "F.CrtYd")
		)
		(fp_rect
			(start -0.4318 0.9525)
			(end 0.4318 -0.9525)
			(stroke
				(width 0)
				(type default)
			)
			(fill no)
			(layer "F.Fab")
		)
		(pad "1" smd custom
			(at 0 -0.4445 180)
			(size 0.1524 0.1524)
			(layers "F.Cu" "F.Mask" "F.Paste")
			(net "P5VA_LL")
			(options
				(clearance outline)
				(anchor circle)
			)
			(primitives
				(gr_poly
					(pts
						(arc
							(start 0.3048 -0.2032)
							(mid 0.275042 -0.275042)
							(end 0.2032 -0.3048)
						)
						(arc
							(start -0.2032 -0.3048)
							(mid -0.275042 -0.275042)
							(end -0.3048 -0.2032)
						)
						(arc
							(start -0.3048 0.2032)
							(mid -0.275042 0.275042)
							(end -0.2032 0.3048)
						)
						(arc
							(start 0.2032 0.3048)
							(mid 0.275042 0.275042)
							(end 0.3048 0.2032)
						)
					)
					(width 0)
					(fill yes)
				)
			)
		)
		(pad "2" smd custom
			(at 0 0.4445 180)
			(size 0.1524 0.1524)
			(layers "F.Cu" "F.Mask" "F.Paste")
			(net "P5VA_SNB")
			(options
				(clearance outline)
				(anchor circle)
			)
			(primitives
				(gr_poly
					(pts
						(arc
							(start 0.3048 -0.2032)
							(mid 0.275042 -0.275042)
							(end 0.2032 -0.3048)
						)
						(arc
							(start -0.2032 -0.3048)
							(mid -0.275042 -0.275042)
							(end -0.3048 -0.2032)
						)
						(arc
							(start -0.3048 0.2032)
							(mid -0.275042 0.275042)
							(end -0.2032 0.3048)
						)
						(arc
							(start 0.2032 0.3048)
							(mid 0.275042 0.275042)
							(end 0.3048 0.2032)
						)
					)
					(width 0)
					(fill yes)
				)
			)
		)
	)
	(footprint ""
		(layer "F.Cu")
		(at 207.8736 -376.0724 -90)
		(property "Reference" "Q32"
			(at 0 0 270)
			(layer "F.SilkS")
			(hide yes)
			(effects
				(font
					(size 1.27 1.27)
				)
			)
		)
		(property "Value" "2N7002DW-7F-GP"
			(at -2.3622 -8.2042 270)
			(unlocked yes)
			(layer "F.Fab")
			(hide yes)
			(effects
				(font
					(size 1.016 1.016)
					(thickness 0.1524)
				)
			)
		)
		(property "Device Type" "SOT-363H44"
			(at -2.3622 -10.1092 270)
			(unlocked yes)
			(layer "F.Fab")
			(hide yes)
			(effects
				(font
					(size 1.016 1.016)
					(thickness 0.1524)
				)
			)
		)
		(duplicate_pad_numbers_are_jumpers no)
		(fp_line
			(start -1.4478 1.7018)
			(end 1.4478 1.7018)
			(stroke
				(width 0.1524)
				(type default)
			)
			(layer "F.SilkS")
		)
		(fp_line
			(start 1.4478 1.7018)
			(end 1.4478 -1.7018)
			(stroke
				(width 0.1524)
				(type default)
			)
			(layer "F.SilkS")
		)
		(fp_line
			(start -1.27 1.524)
			(end -1.27 0.6604)
			(stroke
				(width 0.4826)
				(type default)
			)
			(layer "F.SilkS")
		)
		(fp_line
			(start -1.4478 -1.7018)
			(end -1.4478 1.7018)
			(stroke
				(width 0.1524)
				(type default)
			)
			(layer "F.SilkS")
		)
		(fp_line
			(start 1.4478 -1.7018)
			(end -1.4478 -1.7018)
			(stroke
				(width 0.1524)
				(type default)
			)
			(layer "F.SilkS")
		)
		(fp_poly
			(pts
				(xy -1.524 -1.778) (xy 1.524 -1.778) (xy 1.524 1.778) (xy -1.524 1.778)
			)
			(stroke
				(width 0)
				(type default)
			)
			(fill no)
			(layer "F.CrtYd")
		)
		(fp_poly
			(pts
				(xy -1.524 -1.778) (xy 1.524 -1.778) (xy 1.524 1.778) (xy -1.524 1.778)
			)
			(stroke
				(width 0)
				(type default)
			)
			(fill no)
			(layer "F.Fab")
		)
		(pad "1" smd rect
			(at -0.65024 0.9398 270)
			(size 0.4064 1.016)
			(layers "F.Cu" "F.Mask" "F.Paste")
			(net "P3V3_HDD1_LED")
		)
		(pad "2" smd rect
			(at 0 0.9398 270)
			(size 0.4064 1.016)
			(layers "F.Cu" "F.Mask" "F.Paste")
			(net "HDD1_LED_G")
		)
		(pad "3" smd rect
			(at 0.65024 0.9398 270)
			(size 0.4064 1.016)
			(layers "F.Cu" "F.Mask" "F.Paste")
			(net "P5VA")
		)
		(pad "4" smd rect
			(at 0.65024 -0.9398 270)
			(size 0.4064 1.016)
			(layers "F.Cu" "F.Mask" "F.Paste")
			(net "P5VA_HDD1_LED")
		)
		(pad "5" smd rect
			(at 0 -0.9398 270)
			(size 0.4064 1.016)
			(layers "F.Cu" "F.Mask" "F.Paste")
			(net "HDD1_LED_G")
		)
		(pad "6" smd rect
			(at -0.65024 -0.9398 270)
			(size 0.4064 1.016)
			(layers "F.Cu" "F.Mask" "F.Paste")
			(net "P3V3")
		)
	)
	(footprint ""
		(layer "F.Cu")
		(at 27.2415 -246.888 -90)
		(property "Reference" "R367"
			(at 0 0 270)
			(layer "F.SilkS")
			(hide yes)
			(effects
				(font
					(size 1.27 1.27)
				)
			)
		)
		(property "Value" "4K7R2J-2-GP"
			(at 0.064008 -3.993896 270)
			(unlocked yes)
			(layer "F.Fab")
			(hide yes)
			(effects
				(font
					(size 1.016 1.016)
					(thickness 0.1524)
				)
			)
		)
		(property "Device Type" "R402H16"
			(at 0.064008 -5.517896 270)
			(unlocked yes)
			(layer "F.Fab")
			(hide yes)
			(effects
				(font
					(size 1.016 1.016)
					(thickness 0.1524)
				)
			)
		)
		(duplicate_pad_numbers_are_jumpers no)
		(fp_line
			(start -0.508 -0.9398)
			(end -0.508 0.9398)
			(stroke
				(width 0.1524)
				(type default)
			)
			(layer "F.SilkS")
		)
		(fp_line
			(start 0.508 -0.9398)
			(end -0.508 -0.9398)
			(stroke
				(width 0.1524)
				(type default)
			)
			(layer "F.SilkS")
		)
		(fp_rect
			(start -0.508 0.9398)
			(end 0.508 -0.9398)
			(stroke
				(width 0)
				(type default)
			)
			(fill no)
			(layer "F.CrtYd")
		)
		(fp_rect
			(start -0.508 0.9398)
			(end 0.508 -0.9398)
			(stroke
				(width 0)
				(type default)
			)
			(fill no)
			(layer "F.Fab")
		)
		(pad "1" smd custom
			(at 0 -0.4445 270)
			(size 0.1397 0.1397)
			(layers "F.Cu" "F.Mask" "F.Paste")
			(net "P3V3")
			(options
				(clearance outline)
				(anchor circle)
			)
			(primitives
				(gr_poly
					(pts
						(arc
							(start -0.1778 -0.2794)
							(mid -0.249642 -0.249642)
							(end -0.2794 -0.1778)
						)
						(arc
							(start -0.2794 0.1778)
							(mid -0.249642 0.249642)
							(end -0.1778 0.2794)
						)
						(arc
							(start 0.1778 0.2794)
							(mid 0.249642 0.249642)
							(end 0.2794 0.1778)
						)
						(arc
							(start 0.2794 -0.1778)
							(mid 0.249642 -0.249642)
							(end 0.1778 -0.2794)
						)
					)
					(width 0)
					(fill yes)
				)
			)
		)
		(pad "2" smd custom
			(at 0 0.4445 270)
			(size 0.1397 0.1397)
			(layers "F.Cu" "F.Mask" "F.Paste")
			(net "I2C_B_SCL")
			(options
				(clearance outline)
				(anchor circle)
			)
			(primitives
				(gr_poly
					(pts
						(arc
							(start -0.1778 -0.2794)
							(mid -0.249642 -0.249642)
							(end -0.2794 -0.1778)
						)
						(arc
							(start -0.2794 0.1778)
							(mid -0.249642 0.249642)
							(end -0.1778 0.2794)
						)
						(arc
							(start 0.1778 0.2794)
							(mid 0.249642 0.249642)
							(end 0.2794 0.1778)
						)
						(arc
							(start 0.2794 -0.1778)
							(mid 0.249642 -0.249642)
							(end 0.1778 -0.2794)
						)
					)
					(width 0)
					(fill yes)
				)
			)
		)
	)
)
